(kicad_pcb
	(version 20241229)
	(generator "pcbnew")
	(generator_version "9.0")
	(general
		(thickness 1.61)
		(legacy_teardrops no)
	)
	(paper "A3")
	(title_block
		(title "RDIMM DDR5 Tester")
		(date "2026-05-21")
		(rev "2.2.0")
		(company "Antmicro")
		(comment 9 "footprints 572-574 of 796")
	)
	(layers
		(0 "F.Cu" signal)
		(4 "In1.Cu" power)
		(6 "In2.Cu" mixed)
		(8 "In3.Cu" power)
		(10 "In4.Cu" mixed)
		(12 "In5.Cu" power)
		(14 "In6.Cu" mixed)
		(16 "In7.Cu" power)
		(18 "In8.Cu" power)
		(20 "In9.Cu" mixed)
		(22 "In10.Cu" power)
		(2 "B.Cu" signal)
		(9 "F.Adhes" user "F.Adhesive")
		(11 "B.Adhes" user "B.Adhesive")
		(13 "F.Paste" user)
		(15 "B.Paste" user)
		(5 "F.SilkS" user "F.Silkscreen")
		(7 "B.SilkS" user "B.Silkscreen")
		(1 "F.Mask" user)
		(3 "B.Mask" user)
		(17 "Dwgs.User" user "User.Drawings")
		(19 "Cmts.User" user "User.Comments")
		(21 "Eco1.User" user "User.Eco1")
		(23 "Eco2.User" user "User.Eco2")
		(25 "Edge.Cuts" user)
		(27 "Margin" user)
		(31 "F.CrtYd" user "F.Courtyard")
		(29 "B.CrtYd" user "B.Courtyard")
		(35 "F.Fab" user)
		(33 "B.Fab" user)
	)
	(footprint "antmicro-footprints:X2SON8_1.4x1x0.32mm_P0.35mm"
		(layer "B.Cu")
		(at 118.525 166.79 90)
		(property "Reference" "U44"
			(at -1.98 -1.11 0)
			(layer "B.SilkS")
			(effects
				(font
					(size 0.7 0.7)
					(thickness 0.15)
				)
				(justify right bottom mirror)
			)
		)
		(property "Value" "TXS0102DQER"
			(at 0 -1.929 90)
			(layer "B.Fab")
			(effects
				(font
					(size 0.7 0.7)
					(thickness 0.15)
				)
				(justify right bottom mirror)
			)
		)
		(property "Datasheet" "https://www.ti.com/lit/ds/symlink/txs0102.pdf?ts=1637914596981&ref_url=https%253A%252F%252Fwww.ti.com%252Fstore%252Fti%252Fen%252Fp%252Fproduct%252F%253Fp%253DTXS0102DCTR%2526keyMatch%253DTXS0102DCTR%2526tisearch%253Dsearch-everything%2526usecase%253DOPN"
			(at 0 0 90)
			(layer "F.Fab")
			(hide yes)
			(effects
				(font
					(size 1.27 1.27)
					(thickness 0.15)
				)
			)
		)
		(property "MPN" "TXS0102DQER"
			(at 0 0 90)
			(unlocked yes)
			(layer "B.Fab")
			(hide yes)
			(effects
				(font
					(size 1 1)
					(thickness 0.15)
				)
				(justify mirror)
			)
		)
		(property "Manufacturer" "Texas Instruments"
			(at 0 0 90)
			(unlocked yes)
			(layer "B.Fab")
			(hide yes)
			(effects
				(font
					(size 1 1)
					(thickness 0.15)
				)
				(justify mirror)
			)
		)
		(property "Author" "Antmicro"
			(at 0 0 90)
			(unlocked yes)
			(layer "B.Fab")
			(hide yes)
			(effects
				(font
					(size 1 1)
					(thickness 0.15)
				)
				(justify mirror)
			)
		)
		(property "License" "Apache-2.0"
			(at 0 0 90)
			(unlocked yes)
			(layer "B.Fab")
			(hide yes)
			(effects
				(font
					(size 1 1)
					(thickness 0.15)
				)
				(justify mirror)
			)
		)
		(sheetname "/HDMI + SD Card/")
		(sheetfile "hdmi-sd-card.kicad_sch")
		(attr smd)
		(fp_line
			(start 0.598 -0.801)
			(end 0.498 -0.801)
			(stroke
				(width 0.15)
				(type solid)
			)
			(layer "B.SilkS")
		)
		(fp_line
			(start -0.6 -0.801)
			(end -0.5 -0.801)
			(stroke
				(width 0.15)
				(type solid)
			)
			(layer "B.SilkS")
		)
		(fp_line
			(start 0.598 -0.7)
			(end 0.598 -0.801)
			(stroke
				(width 0.15)
				(type solid)
			)
			(layer "B.SilkS")
		)
		(fp_line
			(start -0.6 -0.7)
			(end -0.6 -0.801)
			(stroke
				(width 0.15)
				(type solid)
			)
			(layer "B.SilkS")
		)
		(fp_line
			(start 0.598 0.7)
			(end 0.598 0.801)
			(stroke
				(width 0.15)
				(type solid)
			)
			(layer "B.SilkS")
		)
		(fp_line
			(start 0.598 0.801)
			(end 0.498 0.801)
			(stroke
				(width 0.15)
				(type solid)
			)
			(layer "B.SilkS")
		)
		(fp_line
			(start -0.402 0.801)
			(end -0.6 0.801)
			(stroke
				(width 0.15)
				(type solid)
			)
			(layer "B.SilkS")
		)
		(fp_line
			(start -0.6 0.801)
			(end -0.6 0.7)
			(stroke
				(width 0.15)
				(type solid)
			)
			(layer "B.SilkS")
		)
		(fp_circle
			(center -0.81 0.77)
			(end -0.81 0.72)
			(stroke
				(width 0.15)
				(type solid)
			)
			(fill yes)
			(layer "B.SilkS")
		)
		(fp_rect
			(start 0.75 0.925)
			(end -0.75 -0.925)
			(stroke
				(width 0.05)
				(type solid)
			)
			(fill no)
			(layer "B.CrtYd")
		)
		(fp_line
			(start -0.5 -0.724)
			(end 0.498 -0.724)
			(stroke
				(width 0.15)
				(type solid)
			)
			(layer "B.Fab")
		)
		(fp_line
			(start 0.498 0.719)
			(end 0.498 -0.719)
			(stroke
				(width 0.15)
				(type solid)
			)
			(layer "B.Fab")
		)
		(fp_line
			(start -0.5 0.724)
			(end 0.498 0.724)
			(stroke
				(width 0.15)
				(type solid)
			)
			(layer "B.Fab")
		)
		(fp_line
			(start -0.5 0.729)
			(end -0.5 -0.719)
			(stroke
				(width 0.15)
				(type solid)
			)
			(layer "B.Fab")
		)
		(fp_text user "Author: Antmicro"
			(at -0.95 -5.129 270)
			(layer "B.Fab")
			(effects
				(font
					(size 0.7 0.7)
					(thickness 0.15)
				)
				(justify left bottom mirror)
			)
		)
		(fp_text user "${REFERENCE}"
			(at -0.95 -3.929 270)
			(layer "B.Fab")
			(effects
				(font
					(size 0.7 0.7)
					(thickness 0.15)
				)
				(justify left bottom mirror)
			)
		)
		(fp_text user "License: Apache-2.0"
			(at -0.95 -6.329 270)
			(layer "B.Fab")
			(effects
				(font
					(size 0.7 0.7)
					(thickness 0.15)
				)
				(justify left bottom mirror)
			)
		)
		(pad "1" smd rect
			(at -0.43 0.526 180)
			(size 0.17 0.5)
			(layers "B.Cu" "B.Mask" "B.Paste")
			(net 151 "+3V3")
			(pinfunction "VCCA")
			(pintype "power_in")
		)
		(pad "2" smd rect
			(at -0.43 0.175 180)
			(size 0.17 0.5)
			(layers "B.Cu" "B.Mask" "B.Paste")
			(net 555 "/FPGA banks HD/HDMI_IN_I2C.SDA")
			(pinfunction "A1")
			(pintype "bidirectional")
		)
		(pad "3" smd rect
			(at -0.43 -0.175 180)
			(size 0.17 0.5)
			(layers "B.Cu" "B.Mask" "B.Paste")
			(net 550 "/FPGA banks HD/HDMI_IN_I2C.SCL")
			(pinfunction "A2")
			(pintype "bidirectional")
		)
		(pad "4" smd rect
			(at -0.43 -0.526 180)
			(size 0.17 0.5)
			(layers "B.Cu" "B.Mask" "B.Paste")
			(net 1 "GND")
			(pinfunction "GND")
			(pintype "power_in")
		)
		(pad "5" smd rect
			(at 0.43 -0.526 180)
			(size 0.17 0.5)
			(layers "B.Cu" "B.Mask" "B.Paste")
			(net 151 "+3V3")
			(pinfunction "OE")
			(pintype "tri_state")
		)
		(pad "6" smd rect
			(at 0.43 -0.175 180)
			(size 0.17 0.5)
			(layers "B.Cu" "B.Mask" "B.Paste")
			(net 499 "/HDMI + SD Card/HDMI_IN_5V.SCL")
			(pinfunction "B2")
			(pintype "bidirectional")
		)
		(pad "7" smd rect
			(at 0.43 0.175 180)
			(size 0.17 0.5)
			(layers "B.Cu" "B.Mask" "B.Paste")
			(net 480 "/HDMI + SD Card/HDMI_IN_5V.SDA")
			(pinfunction "B1")
			(pintype "bidirectional")
		)
		(pad "8" smd rect
			(at 0.43 0.526 180)
			(size 0.17 0.5)
			(layers "B.Cu" "B.Mask" "B.Paste")
			(net 297 "/HDMI + SD Card/HDMI_IN_5V")
			(pinfunction "VCCB")
			(pintype "power_in")
		)
	)
	(footprint "antmicro-footprints:C_0402_1005Metric"
		(layer "B.Cu")
		(at 122.95 153.61 180)
		(descr "Capacitor SMD 0402")
		(tags "capacitor SMD 0402")
		(property "Reference" "C289"
			(at -5.23 -1.79 0)
			(layer "B.SilkS")
			(effects
				(font
					(size 0.7 0.7)
					(thickness 0.15)
				)
				(justify left bottom mirror)
			)
		)
		(property "Value" "C_100n_0402"
			(at -1.022927 -2.155213 0)
			(layer "B.Fab")
			(effects
				(font
					(size 0.7 0.7)
					(thickness 0.15)
				)
				(justify left bottom mirror)
			)
		)
		(property "Datasheet" "https://www.murata.com/products/productdetail?partno=GRM155R61H104KE14%23"
			(at 0 0 180)
			(layer "F.Fab")
			(hide yes)
			(effects
				(font
					(size 1.27 1.27)
					(thickness 0.15)
				)
			)
		)
		(property "Manufacturer" "Murata"
			(at 0 0 180)
			(unlocked yes)
			(layer "B.Fab")
			(hide yes)
			(effects
				(font
					(size 1 1)
					(thickness 0.15)
				)
				(justify mirror)
			)
		)
		(property "MPN" "GRM155R61H104KE14D"
			(at 0 0 180)
			(unlocked yes)
			(layer "B.Fab")
			(hide yes)
			(effects
				(font
					(size 1 1)
					(thickness 0.15)
				)
				(justify mirror)
			)
		)
		(property "Val" "100n"
			(at 0 0 180)
			(unlocked yes)
			(layer "B.Fab")
			(hide yes)
			(effects
				(font
					(size 1 1)
					(thickness 0.15)
				)
				(justify mirror)
			)
		)
		(property "License" "Apache-2.0"
			(at 0 0 180)
			(unlocked yes)
			(layer "B.Fab")
			(hide yes)
			(effects
				(font
					(size 1 1)
					(thickness 0.15)
				)
				(justify mirror)
			)
		)
		(property "Author" "Antmicro"
			(at 0 0 180)
			(unlocked yes)
			(layer "B.Fab")
			(hide yes)
			(effects
				(font
					(size 1 1)
					(thickness 0.15)
				)
				(justify mirror)
			)
		)
		(property "Voltage" "50V"
			(at 0 0 180)
			(unlocked yes)
			(layer "B.Fab")
			(hide yes)
			(effects
				(font
					(size 1 1)
					(thickness 0.15)
				)
				(justify mirror)
			)
		)
		(property "Dielectric" "X5R"
			(at 0 0 180)
			(unlocked yes)
			(layer "B.Fab")
			(hide yes)
			(effects
				(font
					(size 1 1)
					(thickness 0.15)
				)
				(justify mirror)
			)
		)
		(sheetname "/FPGA MGT Interface/")
		(sheetfile "fpga-mgt.kicad_sch")
		(attr smd)
		(fp_rect
			(start -0.925 0.47)
			(end 0.925 -0.47)
			(stroke
				(width 0.05)
				(type default)
			)
			(fill no)
			(layer "B.CrtYd")
		)
		(fp_line
			(start 0.504 0.25)
			(end 0.504 -0.248)
			(stroke
				(width 0.15)
				(type solid)
			)
			(layer "B.Fab")
		)
		(fp_line
			(start 0.504 -0.248)
			(end -0.494 -0.248)
			(stroke
				(width 0.15)
				(type solid)
			)
			(layer "B.Fab")
		)
		(fp_line
			(start -0.494 0.25)
			(end 0.504 0.25)
			(stroke
				(width 0.15)
				(type solid)
			)
			(layer "B.Fab")
		)
		(fp_line
			(start -0.494 -0.248)
			(end -0.494 0.25)
			(stroke
				(width 0.15)
				(type solid)
			)
			(layer "B.Fab")
		)
		(fp_text user "Author: Antmicro"
			(at -0.939 -3.399 0)
			(layer "B.Fab")
			(effects
				(font
					(size 0.7 0.7)
					(thickness 0.15)
				)
				(justify left bottom mirror)
			)
		)
		(fp_text user "${REFERENCE}"
			(at -0.939 -4.599 0)
			(layer "B.Fab")
			(effects
				(font
					(size 0.7 0.7)
					(thickness 0.15)
				)
				(justify left bottom mirror)
			)
		)
		(fp_text user "License: Apache-2.0"
			(at -0.939 -5.799 0)
			(layer "B.Fab")
			(effects
				(font
					(size 0.7 0.7)
					(thickness 0.15)
				)
				(justify left bottom mirror)
			)
		)
		(pad "1" smd roundrect
			(at -0.48 0 180)
			(size 0.59 0.64)
			(layers "B.Cu" "B.Mask" "B.Paste")
			(roundrect_rratio 0.25)
			(net 268 "/FPGA MGT Interface/HDMI_IN_CLK_C_P")
			(pintype "passive")
		)
		(pad "2" smd roundrect
			(at 0.48 0 180)
			(size 0.59 0.64)
			(layers "B.Cu" "B.Mask" "B.Paste")
			(roundrect_rratio 0.25)
			(net 269 "/FPGA MGT Interface/HDMI_IN.CLK_P")
			(pintype "passive")
		)
	)
	(footprint "antmicro-footprints:USON-10_2.5x1mm_P0.5mm"
		(layer "B.Cu")
		(at 107.804 157.119 180)
		(descr "USON-10 2.5x1mm_ Pitch 0.5mm")
		(tags "USON-10 2.5x1mm Pitch 0.5mm")
		(property "Reference" "U37"
			(at -2.046 -0.731 90)
			(layer "B.SilkS")
			(effects
				(font
					(size 0.7 0.7)
					(thickness 0.15)
				)
				(justify right bottom mirror)
			)
		)
		(property "Value" "TPD4E05U06QDQARQ1"
			(at 0.018 -2.499 0)
			(layer "B.Fab")
			(effects
				(font
					(size 0.7 0.7)
					(thickness 0.15)
				)
				(justify left bottom mirror)
			)
		)
		(property "Datasheet" "https://www.ti.com/lit/ds/symlink/tpd4e05u06-q1.pdf?HQS=dis-mous-null-mousermode-dsf-pf-null-wwe&ts=1663591265741&ref_url=https%253A%252F%252Fwww.mouser.com%252F"
			(at 0 0 180)
			(layer "F.Fab")
			(hide yes)
			(effects
				(font
					(size 1.27 1.27)
					(thickness 0.15)
				)
			)
		)
		(property "Manufacturer" "Texas Instruments"
			(at 0 0 180)
			(unlocked yes)
			(layer "B.Fab")
			(hide yes)
			(effects
				(font
					(size 1 1)
					(thickness 0.15)
				)
				(justify mirror)
			)
		)
		(property "MPN" "TPD4E05U06QDQARQ1"
			(at 0 0 180)
			(unlocked yes)
			(layer "B.Fab")
			(hide yes)
			(effects
				(font
					(size 1 1)
					(thickness 0.15)
				)
				(justify mirror)
			)
		)
		(property "Author" "Antmicro"
			(at 0 0 180)
			(unlocked yes)
			(layer "B.Fab")
			(hide yes)
			(effects
				(font
					(size 1 1)
					(thickness 0.15)
				)
				(justify mirror)
			)
		)
		(property "License" "Apache-2.0"
			(at 0 0 180)
			(unlocked yes)
			(layer "B.Fab")
			(hide yes)
			(effects
				(font
					(size 1 1)
					(thickness 0.15)
				)
				(justify mirror)
			)
		)
		(sheetname "/HDMI + SD Card/")
		(sheetfile "hdmi-sd-card.kicad_sch")
		(attr smd)
		(fp_line
			(start 0.498 1.401)
			(end -0.5 1.401)
			(stroke
				(width 0.15)
				(type solid)
			)
			(layer "B.SilkS")
		)
		(fp_line
			(start 0.498 -1.398)
			(end -0.5 -1.398)
			(stroke
				(width 0.15)
				(type solid)
			)
			(layer "B.SilkS")
		)
		(fp_circle
			(center -0.68 1.27)
			(end -0.63 1.27)
			(stroke
				(width 0.15)
				(type solid)
			)
			(fill yes)
			(layer "B.SilkS")
		)
		(fp_rect
			(start -0.8 1.5)
			(end 0.8 -1.499)
			(stroke
				(width 0.05)
				(type solid)
			)
			(fill no)
			(layer "B.CrtYd")
		)
		(fp_line
			(start 0.498 1.25)
			(end 0.498 -1.249)
			(stroke
				(width 0.15)
				(type solid)
			)
			(layer "B.Fab")
		)
		(fp_line
			(start 0.498 1.25)
			(end -0.25 1.25)
			(stroke
				(width 0.15)
				(type solid)
			)
			(layer "B.Fab")
		)
		(fp_line
			(start -0.25 1.25)
			(end -0.5 1)
			(stroke
				(width 0.15)
				(type solid)
			)
			(layer "B.Fab")
		)
		(fp_line
			(start -0.5 1)
			(end -0.5 -1.249)
			(stroke
				(width 0.15)
				(type solid)
			)
			(layer "B.Fab")
		)
		(fp_line
			(start -0.5 -1.249)
			(end 0.498 -1.249)
			(stroke
				(width 0.15)
				(type solid)
			)
			(layer "B.Fab")
		)
		(fp_text user "Author: Antmicro"
			(at -0.802 -5.7 0)
			(layer "B.Fab")
			(effects
				(font
					(size 0.7 0.7)
					(thickness 0.15)
				)
				(justify left bottom mirror)
			)
		)
		(fp_text user "License: Apache-2.0"
			(at -0.802 -6.9 0)
			(layer "B.Fab")
			(effects
				(font
					(size 0.7 0.7)
					(thickness 0.15)
				)
				(justify left bottom mirror)
			)
		)
		(fp_text user "${REFERENCE}"
			(at -0.802 -4.498 0)
			(layer "B.Fab")
			(effects
				(font
					(size 0.7 0.7)
					(thickness 0.15)
				)
				(justify left bottom mirror)
			)
		)
		(pad "1" smd roundrect
			(at -0.387 1 270)
			(size 0.25 0.55)
			(layers "B.Cu" "B.Mask" "B.Paste")
			(roundrect_rratio 0.25)
			(net 344 "/FPGA MGT Interface/HDMI_IN.D2_P")
			(pintype "passive")
		)
		(pad "2" smd roundrect
			(at -0.387 0.5 270)
			(size 0.25 0.55)
			(layers "B.Cu" "B.Mask" "B.Paste")
			(roundrect_rratio 0.25)
			(net 342 "/FPGA MGT Interface/HDMI_IN.D2_N")
			(pintype "passive")
		)
		(pad "3" smd roundrect
			(at -0.387 0 270)
			(size 0.4 0.55)
			(layers "B.Cu" "B.Mask" "B.Paste")
			(roundrect_rratio 0.25)
			(net 1 "GND")
			(pintype "power_in")
		)
		(pad "4" smd roundrect
			(at -0.387 -0.498 270)
			(size 0.25 0.55)
			(layers "B.Cu" "B.Mask" "B.Paste")
			(roundrect_rratio 0.25)
			(net 348 "/FPGA MGT Interface/HDMI_IN.D1_P")
			(pintype "passive")
		)
		(pad "5" smd roundrect
			(at -0.387 -0.998 270)
			(size 0.25 0.55)
			(layers "B.Cu" "B.Mask" "B.Paste")
			(roundrect_rratio 0.25)
			(net 346 "/FPGA MGT Interface/HDMI_IN.D1_N")
			(pintype "passive")
		)
		(pad "6" smd roundrect
			(at 0.385 -0.998 270)
			(size 0.25 0.55)
			(layers "B.Cu" "B.Mask" "B.Paste")
			(roundrect_rratio 0.25)
			(net 346 "/FPGA MGT Interface/HDMI_IN.D1_N")
			(pintype "passive")
		)
		(pad "7" smd roundrect
			(at 0.385 -0.498 270)
			(size 0.25 0.55)
			(layers "B.Cu" "B.Mask" "B.Paste")
			(roundrect_rratio 0.25)
			(net 348 "/FPGA MGT Interface/HDMI_IN.D1_P")
			(pintype "passive")
		)
		(pad "8" smd roundrect
			(at 0.385 0 270)
			(size 0.4 0.55)
			(layers "B.Cu" "B.Mask" "B.Paste")
			(roundrect_rratio 0.25)
			(net 1 "GND")
			(pintype "passive")
		)
		(pad "9" smd roundrect
			(at 0.385 0.5 270)
			(size 0.25 0.55)
			(layers "B.Cu" "B.Mask" "B.Paste")
			(roundrect_rratio 0.25)
			(net 342 "/FPGA MGT Interface/HDMI_IN.D2_N")
			(pintype "passive")
		)
		(pad "10" smd roundrect
			(at 0.385 1 270)
			(size 0.25 0.55)
			(layers "B.Cu" "B.Mask" "B.Paste")
			(roundrect_rratio 0.25)
			(net 344 "/FPGA MGT Interface/HDMI_IN.D2_P")
			(pintype "passive")
		)
	)
)
